;LEADER: 12 
;HEADER: 
;CODE  : ASCII 
;FILE  : 9324_DA0F0TMBIJ0_F0T_Motherboard_J_v01_20230324_0910-bd-18-4.drl for backdrilling ... from layer BOTTOM to layer GND1
;DESIGN: 9324_DA0F0TMBIJ0_F0T_Motherboard_J_v01_20230324_0910.brd
;MUST-NOT-CUT-LAYER = IN1,  MAX_DRILL_DEPTH = 83.20 MILS,  MFG_STUB_LENGTH = 0.00 MILS
;   BackdrillSize 1. = 15.700000 Tolerance = +0.000000/-0.000000 NON_PLATED MILS Quantity = 1188
;   BackdrillSize 2. = 17.700000 Tolerance = +0.000000/-0.000000 NON_PLATED MILS Quantity = 212
%
G90
X0171341Y0964239
X0155199Y0967585
X0171341Y1051247
X0155199Y1054593
X0171341Y1024475
X0171341Y1021129
X0201141Y1225263
X0184899Y1231955
X0201141Y1228609
X0184899Y1228609
X0201141Y1211877
X0201141Y1218570
X0184899Y1215223
X0184899Y1221916
X0201141Y1235302
X0201141Y1241995
X0184899Y1238648
X0184899Y1245341
X0260441Y1188452
X0244299Y1195144
X0260441Y1191798
X0244299Y1191798
X0244299Y1201837
X0244299Y1208530
X0244299Y1185105
X0260441Y1198491
X0260441Y1205184
X0201141Y1151641
X0184899Y1084711
X0184899Y1158333
X0201141Y1154988
X0184899Y1154987
X0201141Y1138255
X0201141Y1144948
X0184899Y1141601
X0184899Y1148294
X0201141Y1161680
X0201141Y1168373
X0184899Y1165026
X0184899Y1171719
X0201141Y1088059
X0201141Y1094752
X0184899Y1091404
X0184899Y1098097
X0260441Y1175066
X0260441Y1181759
X0244299Y1178412
X0201041Y0984318
X0184899Y0987664
X0201041Y0991011
X0184899Y0994357
X0184899Y1021129
X0201141Y1078018
X0201141Y1081366
X0184899Y1081365
X0201141Y1051247
X0184899Y1054593
X0201141Y1064633
X0201141Y1071326
X0184899Y1067979
X0184899Y1074672
X0184899Y1027822
X0201141Y1031168
X0184899Y1034515
X0201141Y1037861
X0184899Y1041207
X0201141Y1044554
X0184899Y1047900
X0201141Y1024475
X0201141Y1021129
X0201041Y0970932
X0184899Y0937467
X0201041Y0930774
X0184899Y0934121
X0201041Y0934121
X0201041Y0964239
X0184899Y0967585
X0201041Y0940814
X0201041Y0947507
X0184899Y0944160
X0184899Y0950853
X0201041Y0917389
X0201041Y0924081
X0184899Y0920735
X0184899Y0927428
X0184899Y0974278
X0201041Y0977625
X0184899Y0980971
X0260441Y0893963
X0244299Y0900656
X0260441Y0897310
X0244299Y0897310
X0260441Y0887270
X0244299Y0883924
X0244299Y0890617
X0260441Y0904003
X0260441Y0910696
X0244299Y0907349
X0244299Y0914042
X0201041Y0820341
X0201041Y0857152
X0184899Y0827034
X0184899Y0863845
X0201041Y0823688
X0201041Y0860499
X0184899Y0823688
X0184899Y0860499
X0184899Y0870538
X0184899Y0877231
X0201041Y0806955
X0201041Y0813648
X0184899Y0810302
X0184899Y0816995
X0201041Y0830381
X0201041Y0837074
X0184899Y0833727
X0184899Y0840420
X0201041Y0843766
X0201041Y0850459
X0184899Y0847113
X0184899Y0853806
X0201041Y0867192
X0201041Y0873885
X0260441Y0880577
X0358129Y0973143
X0347030Y0953917
X0358129Y0896240
X0358129Y0915466
X0354429Y0953917
X0350729Y0896240
X0350729Y0915466
X0350729Y0953917
X0354429Y0896240
X0354429Y0915466
X0358129Y0953917
X0347029Y0896240
X0347029Y0915466
X0348878Y0918670
X0350729Y0921875
X0354429Y0889832
X0356278Y0893036
X0350729Y0889832
X0348878Y0893036
X0356278Y0899445
X0354429Y0902649
X0348878Y0899445
X0350729Y0902649
X0354429Y0909057
X0356278Y0912262
X0350729Y0909057
X0348878Y0912262
X0356278Y0918670
X0354429Y0921875
X0354429Y0966735
X0356278Y0969939
X0350729Y0966735
X0348878Y0969939
X0356278Y0957122
X0354429Y0960326
X0348878Y0957122
X0350729Y0960326
X0354429Y0947509
X0356278Y0950713
X0350729Y0947509
X0348878Y0950713
X0347029Y0973143
X0356278Y0976347
X0348878Y0976347
X0354429Y0979552
X0350729Y0979552
X0363678Y0976347
X0361829Y0979552
X0367378Y0976347
X0369229Y0979552
X0371078Y0982756
X0363678Y0982756
X0367378Y0982756
X0359978Y0982756
X0358129Y0934691
X0350729Y0934691
X0354429Y0934691
X0347029Y0934691
X0354429Y0928283
X0356278Y0931488
X0350729Y0928283
X0348879Y0931488
X0356278Y0937896
X0354429Y0941100
X0348878Y0937896
X0350729Y0941100
X0358562Y1025318
X0358562Y1044544
X0358562Y1082995
X0351162Y1025318
X0351161Y1044544
X0351161Y1082995
X0354862Y1025318
X0354861Y1044544
X0354861Y1082995
X0347461Y1025318
X0347461Y1044544
X0347461Y1082995
X0354861Y1076587
X0356711Y1079791
X0351161Y1076587
X0349311Y1079791
X0354861Y1038136
X0356711Y1041340
X0351161Y1038136
X0349311Y1041340
X0356711Y1047749
X0354861Y1050952
X0349311Y1047749
X0351161Y1050952
X0356711Y1009297
X0354861Y1012501
X0349311Y1009297
X0351161Y1012501
X0354861Y1018910
X0356711Y1022114
X0351161Y1018910
X0349311Y1022114
X0356711Y1028523
X0354861Y1031727
X0349311Y1028523
X0351162Y1031727
X0354861Y0999684
X0351161Y0999684
X0356711Y1002888
X0349311Y1002888
X0358562Y1006093
X0347461Y1006093
X0354861Y1063770
X0351161Y1063770
X0358562Y1063770
X0347461Y1063770
X0349311Y1066974
X0351162Y1070178
X0354861Y1057361
X0356711Y1060565
X0351161Y1057361
X0349311Y1060565
X0356711Y1066974
X0354861Y1070178
X0369662Y1127856
X0365962Y1121447
X0362262Y1127856
X0356712Y1124651
X0354861Y1127856
X0371511Y1124651
X0367811Y1124651
X0364111Y1124651
X0360412Y1124651
X0358561Y1121447
X0353011Y1124651
X0356711Y1086200
X0354861Y1089404
X0349311Y1086200
X0351161Y1089404
X0388162Y1121447
X0384462Y1127856
X0380762Y1121447
X0377062Y1127856
X0373362Y1121447
X0410362Y1121447
X0406662Y1127856
X0402962Y1121447
X0399262Y1127856
X0393711Y1124651
X0391862Y1127856
X0386311Y1124651
X0382611Y1124651
X0378911Y1124651
X0375211Y1124651
X0408511Y1124651
X0404811Y1124651
X0401111Y1124651
X0397411Y1124651
X0395562Y1121447
X0390011Y1124651
X0471411Y1124651
X0469562Y1121447
X0441378Y0886627
X0448778Y0886627
X0456178Y0886627
X0463578Y0886627
X0419178Y0886627
X0426578Y0886627
X0433978Y0886627
X0470978Y0886627
X0435829Y0883423
X0443229Y0883423
X0450629Y0883423
X0458029Y0883423
X0465429Y0883423
X0413629Y0883423
X0421029Y0883423
X0428429Y0883423
X0437678Y0880219
X0439529Y0883423
X0445078Y0880219
X0446929Y0883423
X0452479Y0880219
X0454329Y0883423
X0459878Y0880219
X0461729Y0883423
X0467278Y0880219
X0415478Y0880219
X0417329Y0883423
X0422878Y0880219
X0424729Y0883423
X0430278Y0880219
X0432129Y0883423
X0469129Y0883423
X0543129Y0877014
X0535729Y0877014
X0546828Y0877014
X0539428Y0877014
X0543129Y0870606
X0544979Y0873810
X0539429Y0870606
X0537578Y0873810
X0544979Y0880219
X0543129Y0883423
X0537578Y0880219
X0539429Y0883423
X0533879Y0963530
X0522778Y0944304
X0530179Y0905853
X0530178Y0944304
X0522778Y0905853
X0526479Y0944304
X0533879Y0905853
X0533879Y0944304
X0526479Y0905853
X0524629Y0909057
X0526479Y0912262
X0530178Y0899445
X0532029Y0902649
X0526479Y0899445
X0524629Y0902649
X0532029Y0909057
X0530179Y0912262
X0526479Y0957122
X0524629Y0960326
X0530178Y0957122
X0532029Y0960326
X0532029Y0947509
X0530178Y0950713
X0524629Y0947509
X0526479Y0950713
X0530179Y0937896
X0532029Y0941100
X0526479Y0937896
X0524629Y0941100
X0522778Y0963530
X0532029Y0966735
X0524629Y0966735
X0530179Y0969939
X0526479Y0969939
X0530179Y0925079
X0522778Y0925079
X0533879Y0925079
X0526479Y0925079
X0530179Y0918670
X0532029Y0921875
X0526479Y0918670
X0524629Y0921875
X0532029Y0928283
X0530179Y0931488
X0524629Y0928283
X0526479Y0931488
X0512111Y1009297
X0513962Y1012501
X0519511Y1009297
X0530611Y1034931
X0530611Y1054157
X0523211Y1034931
X0526911Y1054157
X0534311Y1034931
X0534311Y1054157
X0526911Y1034931
X0523211Y1054157
X0530611Y1047749
X0532462Y1050953
X0526911Y1047749
X0525061Y1050952
X0532462Y1057361
X0530611Y1060565
X0525062Y1057361
X0526911Y1060565
X0525062Y1018910
X0526911Y1022114
X0532461Y1018910
X0530611Y1022114
X0530611Y1028523
X0532461Y1031727
X0526911Y1028523
X0525062Y1031727
X0532461Y1038136
X0530611Y1041340
X0525062Y1038136
X0526911Y1041340
X0517662Y1012501
X0530611Y1009297
X0526911Y1009297
X0532461Y1012501
X0525062Y1012501
X0534311Y1015705
X0523211Y1015705
X0510262Y1006093
X0521362Y1006093
X0513962Y1006093
X0517662Y1006093
X0530611Y1073383
X0526911Y1073383
X0534311Y1073383
X0523211Y1073383
X0525062Y1076587
X0526911Y1079791
X0530611Y1066974
X0532462Y1070178
X0526911Y1066974
X0525062Y1070178
X0532462Y1076587
X0530611Y1079791
X0493611Y1124651
X0497311Y1124651
X0501011Y1124651
X0504711Y1124651
X0508411Y1124651
X0512111Y1124651
X0515811Y1124651
X0519511Y1124651
X0523211Y1124651
X0475111Y1124651
X0478811Y1124651
X0482511Y1124651
X0486211Y1124651
X0489911Y1124651
X0525062Y1127856
X0491762Y1121447
X0495462Y1127856
X0499162Y1121447
X0502862Y1127856
X0506562Y1121447
X0510262Y1127856
X0513962Y1121447
X0517662Y1127856
X0521362Y1121447
X0473262Y1127856
X0476962Y1121447
X0480662Y1127856
X0484362Y1121447
X0488062Y1127856
X0526911Y1124651
X0530611Y1092608
X0523211Y1092608
X0534310Y1092608
X0526911Y1092608
X0530611Y1086200
X0532462Y1089404
X0526911Y1086200
X0525062Y1089404
X0530611Y1099017
X0525062Y1095813
X0532461Y1095813
X0521362Y1095813
X0636941Y1188451
X0620799Y1195144
X0636941Y1191798
X0620799Y1191798
X0620799Y1201837
X0620799Y1208530
X0620799Y1185105
X0636941Y1198491
X0636941Y1205184
X0636941Y1175066
X0636941Y1181759
X0620799Y1178412
X0636941Y0893963
X0620799Y0900656
X0636941Y0897310
X0620799Y0897310
X0636941Y0887270
X0620799Y0883924
X0620799Y0890617
X0636941Y0904003
X0636941Y0910696
X0620799Y0907349
X0620799Y0914042
X0636941Y0880577
X0696441Y0820341
X0696441Y0857152
X0680299Y0827034
X0680299Y0863845
X0696441Y0823688
X0696441Y0860499
X0680299Y0823688
X0680299Y0860499
X0680299Y0870538
X0680299Y0877231
X0696441Y0806955
X0696441Y0813648
X0680299Y0810302
X0680299Y0816995
X0696441Y0830381
X0696441Y0837074
X0680299Y0833727
X0680299Y0840420
X0696441Y0843766
X0696441Y0850459
X0680299Y0847113
X0680299Y0853806
X0696441Y0867192
X0696441Y0873885
X0696441Y0970932
X0680299Y0937467
X0696441Y0930774
X0680299Y0934121
X0696441Y0934121
X0696441Y0964239
X0680299Y0967585
X0726141Y0964239
X0709999Y0967585
X0696441Y0940814
X0696441Y0947507
X0680299Y0944160
X0680299Y0950853
X0696441Y0917389
X0696441Y0924081
X0680299Y0920735
X0680299Y0927428
X0680299Y0974278
X0696441Y0977625
X0680299Y0980971
X0696441Y0984318
X0680299Y0987664
X0696441Y0991011
X0680299Y0994357
X0680299Y1021129
X0696441Y1078018
X0696441Y1081365
X0680299Y1081365
X0696441Y1051247
X0679999Y1054593
X0726141Y1051247
X0709999Y1054593
X0696441Y1064633
X0696441Y1071325
X0680299Y1067979
X0680299Y1074672
X0679999Y1027822
X0696441Y1031168
X0679999Y1034514
X0696141Y1037861
X0679999Y1041207
X0696141Y1044554
X0679999Y1047900
X0696441Y1024475
X0726141Y1024475
X0696441Y1021129
X0726141Y1021129
X0696441Y1151640
X0680299Y1084711
X0680299Y1158333
X0696441Y1154987
X0680299Y1154987
X0696441Y1138255
X0696441Y1144947
X0680299Y1141601
X0680299Y1148294
X0696441Y1161680
X0696441Y1168373
X0680299Y1165026
X0680299Y1171719
X0696441Y1088058
X0696441Y1094751
X0680299Y1091404
X0680299Y1098097
X0696441Y1225262
X0680299Y1231955
X0696441Y1228609
X0680299Y1228609
X0696441Y1211877
X0696441Y1218569
X0680299Y1215223
X0680299Y1221916
X0696441Y1235302
X0696441Y1241995
X0680299Y1238648
X0680299Y1245341
X1161041Y0827034
X1161041Y0863845
X1161041Y0823688
X1161041Y0860499
X1161041Y0870538
X1161041Y0877231
X1161041Y0810302
X1161041Y0816995
X1161041Y0833727
X1161041Y0840420
X1161041Y0847113
X1161041Y0853806
X1161041Y0937467
X1161041Y0934121
X1161041Y0967585
X1147483Y0964239
X1131341Y0967585
X1161041Y0944160
X1161041Y0950853
X1161041Y0920735
X1161041Y0927428
X1161041Y0974278
X1161041Y0980971
X1161041Y0987664
X1161041Y0994357
X1161041Y1021129
X1161041Y1081365
X1161041Y1054593
X1147483Y1051247
X1131341Y1054593
X1161041Y1067979
X1161041Y1074672
X1161041Y1027822
X1161041Y1034515
X1161041Y1041207
X1161041Y1047900
X1147483Y1024475
X1147483Y1021129
X1161041Y1084711
X1161041Y1158333
X1161041Y1154987
X1161041Y1141601
X1161041Y1148294
X1161041Y1165026
X1161041Y1171719
X1161041Y1091404
X1161041Y1098097
X1161041Y1231955
X1161041Y1228609
X1161041Y1215223
X1161041Y1221916
X1161041Y1238648
X1161041Y1245341
X1177283Y1225263
X1177283Y1228609
X1177283Y1211877
X1177283Y1218570
X1177283Y1235302
X1177250Y1241995
X1236583Y1188452
X1220441Y1195144
X1236583Y1191798
X1220441Y1191798
X1220441Y1201837
X1220441Y1208530
X1220441Y1185105
X1236583Y1198491
X1236583Y1205184
X1177283Y1151641
X1177283Y1154988
X1177283Y1138255
X1177283Y1144948
X1177283Y1161680
X1177283Y1168373
X1177283Y1088059
X1177283Y1094752
X1236583Y1175066
X1236583Y1181759
X1220441Y1178412
X1177183Y0984318
X1177183Y0991011
X1177283Y1078018
X1177283Y1081366
X1177283Y1051247
X1177283Y1064633
X1177283Y1071326
X1177283Y1031168
X1177283Y1037861
X1177283Y1044554
X1177283Y1024475
X1177283Y1021129
X1177183Y0970932
X1177183Y0930774
X1177183Y0934121
X1177183Y0964239
X1177183Y0940814
X1177183Y0947507
X1177183Y0917389
X1177183Y0924081
X1177183Y0977625
X1236583Y0893963
X1220441Y0900656
X1236583Y0897310
X1220441Y0897310
X1236583Y0887270
X1220441Y0883924
X1220441Y0890617
X1236583Y0904003
X1236583Y0910696
X1220441Y0907349
X1220441Y0914042
X1177183Y0820341
X1177183Y0857152
X1177183Y0823688
X1177183Y0860499
X1177183Y0806955
X1177183Y0813648
X1177183Y0830381
X1177183Y0837074
X1177183Y0843766
X1177183Y0850459
X1177183Y0867192
X1177183Y0873885
X1236583Y0880577
X1355765Y0199999
X1355771Y0196298
X1355765Y0203699
X1352561Y0198148
X1334271Y0973143
X1323172Y0953917
X1334271Y0896240
X1334271Y0915466
X1330571Y0953917
X1326871Y0896240
X1326871Y0915466
X1326871Y0953917
X1330571Y0896240
X1330571Y0915466
X1334271Y0953917
X1323171Y0896240
X1323171Y0915466
X1325020Y0918670
X1326871Y0921875
X1330571Y0889832
X1332420Y0893036
X1326871Y0889832
X1325020Y0893036
X1332420Y0899445
X1330571Y0902649
X1325020Y0899445
X1326871Y0902649
X1330571Y0909057
X1332420Y0912262
X1326871Y0909057
X1325020Y0912262
X1332420Y0918670
X1330571Y0921875
X1330571Y0966735
X1332420Y0969939
X1326871Y0966735
X1325020Y0969939
X1332420Y0957122
X1330571Y0960326
X1325020Y0957122
X1326871Y0960326
X1330571Y0947509
X1332420Y0950713
X1326871Y0947509
X1325020Y0950713
X1323171Y0973143
X1332420Y0976347
X1325020Y0976347
X1330571Y0979552
X1326871Y0979552
X1339820Y0976347
X1337971Y0979552
X1343520Y0976347
X1345371Y0979552
X1347220Y0982756
X1339820Y0982756
X1343520Y0982756
X1336120Y0982756
X1334271Y0934691
X1326871Y0934691
X1330571Y0934691
X1323171Y0934691
X1330571Y0928283
X1332420Y0931488
X1326871Y0928283
X1325021Y0931488
X1332420Y0937896
X1330571Y0941100
X1325020Y0937896
X1326871Y0941100
X1334704Y1025318
X1334704Y1044544
X1334704Y1082995
X1327304Y1025318
X1327303Y1044544
X1327303Y1082995
X1331004Y1025318
X1331003Y1044544
X1331003Y1082995
X1323603Y1025318
X1323603Y1044544
X1323603Y1082995
X1331003Y1076587
X1332853Y1079791
X1327303Y1076587
X1325453Y1079791
X1331003Y1038136
X1332853Y1041340
X1327303Y1038136
X1325453Y1041340
X1332853Y1047749
X1331003Y1050952
X1325453Y1047749
X1327303Y1050952
X1332853Y1009297
X1331003Y1012501
X1325453Y1009297
X1327303Y1012501
X1331003Y1018910
X1332853Y1022114
X1327303Y1018910
X1325453Y1022114
X1332853Y1028523
X1331003Y1031727
X1325453Y1028523
X1327304Y1031727
X1331003Y0999684
X1327303Y0999684
X1332853Y1002888
X1325453Y1002888
X1334704Y1006093
X1323603Y1006093
X1331003Y1063770
X1327303Y1063770
X1334704Y1063770
X1323603Y1063770
X1325453Y1066974
X1327304Y1070178
X1331003Y1057361
X1332853Y1060565
X1327303Y1057361
X1325453Y1060565
X1332853Y1066974
X1331003Y1070178
X1364304Y1121447
X1360604Y1127856
X1356904Y1121447
X1353204Y1127856
X1349504Y1121447
X1345804Y1127856
X1342104Y1121447
X1338404Y1127856
X1332854Y1124651
X1369853Y1124651
X1368004Y1127856
X1331003Y1127856
X1362453Y1124651
X1358753Y1124651
X1355053Y1124651
X1351353Y1124651
X1347653Y1124651
X1343953Y1124651
X1340253Y1124651
X1336554Y1124651
X1334703Y1121447
X1371704Y1121447
X1366153Y1124651
X1329153Y1124651
X1332853Y1086200
X1331003Y1089404
X1325453Y1086200
X1327303Y1089404
X1386504Y1121447
X1382804Y1127856
X1379104Y1121447
X1375404Y1127856
X1384653Y1124651
X1380953Y1124651
X1377253Y1124651
X1373553Y1124651
X1469753Y1124651
X1447553Y1124651
X1451253Y1124651
X1454953Y1124651
X1458653Y1124651
X1462353Y1124651
X1466053Y1124651
X1467904Y1121447
X1471604Y1127856
X1445704Y1121447
X1449404Y1127856
X1453104Y1121447
X1456804Y1127856
X1460504Y1121447
X1464204Y1127856
X1417520Y0886627
X1424920Y0886627
X1432320Y0886627
X1439720Y0886627
X1395320Y0886627
X1402720Y0886627
X1410120Y0886627
X1447120Y0886627
X1411971Y0883423
X1419371Y0883423
X1426771Y0883423
X1434171Y0883423
X1441571Y0883423
X1389771Y0883423
X1397171Y0883423
X1404571Y0883423
X1413820Y0880219
X1415671Y0883423
X1421220Y0880219
X1423071Y0883423
X1428621Y0880219
X1430471Y0883423
X1436020Y0880219
X1437871Y0883423
X1443420Y0880219
X1391620Y0880219
X1393471Y0883423
X1399020Y0880219
X1400871Y0883423
X1406420Y0880219
X1408271Y0883423
X1445271Y0883423
X1519271Y0877014
X1511871Y0877014
X1522970Y0877014
X1515570Y0877014
X1519271Y0870606
X1521121Y0873810
X1515571Y0870606
X1513720Y0873810
X1521121Y0880219
X1519271Y0883423
X1513720Y0880219
X1515571Y0883423
X1510021Y0963530
X1498920Y0944304
X1506321Y0905853
X1506320Y0944304
X1498920Y0905853
X1502621Y0944304
X1510021Y0905853
X1510021Y0944304
X1502621Y0905853
X1500771Y0909057
X1502621Y0912262
X1506320Y0899445
X1508171Y0902649
X1502621Y0899445
X1500771Y0902649
X1508171Y0909057
X1506321Y0912262
X1502621Y0957122
X1500771Y0960326
X1506320Y0957122
X1508171Y0960326
X1508171Y0947509
X1506320Y0950713
X1500771Y0947509
X1502621Y0950713
X1506321Y0937896
X1508171Y0941100
X1502621Y0937896
X1500771Y0941100
X1498920Y0963530
X1508171Y0966735
X1500771Y0966735
X1506321Y0969939
X1502621Y0969939
X1506321Y0925079
X1498920Y0925079
X1510021Y0925079
X1502621Y0925079
X1506321Y0918670
X1508171Y0921875
X1502621Y0918670
X1500771Y0921875
X1508171Y0928283
X1506321Y0931488
X1500771Y0928283
X1502621Y0931488
X1488253Y1009297
X1490104Y1012501
X1495653Y1009297
X1506753Y1034931
X1506753Y1054157
X1499353Y1034931
X1503053Y1054157
X1510453Y1034931
X1510453Y1054157
X1503053Y1034931
X1499353Y1054157
X1506753Y1047749
X1508604Y1050953
X1503053Y1047749
X1501203Y1050952
X1508604Y1057361
X1506753Y1060565
X1501204Y1057361
X1503053Y1060565
X1501204Y1018910
X1503053Y1022114
X1508603Y1018910
X1506753Y1022114
X1506753Y1028523
X1508603Y1031727
X1503053Y1028523
X1501204Y1031727
X1508603Y1038136
X1506753Y1041340
X1501204Y1038136
X1503053Y1041340
X1493804Y1012501
X1506753Y1009297
X1503053Y1009297
X1508603Y1012501
X1501204Y1012501
X1510453Y1015705
X1499353Y1015705
X1486404Y1006093
X1497504Y1006093
X1490104Y1006093
X1493804Y1006093
X1506753Y1073383
X1503053Y1073383
X1510453Y1073383
X1499353Y1073383
X1501204Y1076587
X1503053Y1079791
X1506753Y1066974
X1508604Y1070178
X1503053Y1066974
X1501204Y1070178
X1508604Y1076587
X1506753Y1079791
X1473453Y1124651
X1477153Y1124651
X1480853Y1124651
X1484553Y1124651
X1488253Y1124651
X1491953Y1124651
X1495653Y1124651
X1499353Y1124651
X1501204Y1127856
X1475304Y1121447
X1479004Y1127856
X1482704Y1121447
X1486404Y1127856
X1490104Y1121447
X1493804Y1127856
X1497504Y1121447
X1503053Y1124651
X1506753Y1092608
X1499353Y1092608
X1510452Y1092608
X1503053Y1092608
X1506753Y1086200
X1508604Y1089404
X1503053Y1086200
X1501204Y1089404
X1506753Y1099017
X1501204Y1095813
X1508603Y1095813
X1497504Y1095813
X1656441Y1231955
X1656441Y1228609
X1656441Y1215223
X1656441Y1221916
X1656441Y1238648
X1656441Y1245341
X1613083Y1188451
X1596941Y1195144
X1613083Y1191798
X1596941Y1191798
X1596941Y1201837
X1596941Y1208530
X1596941Y1185105
X1613083Y1198491
X1613083Y1205184
X1656441Y1084711
X1656441Y1158333
X1656441Y1154987
X1656441Y1141601
X1656441Y1148294
X1656441Y1165026
X1656441Y1171719
X1656441Y1091404
X1656441Y1098097
X1613083Y1175066
X1613083Y1181759
X1596941Y1178412
X1656441Y0987664
X1656441Y0994357
X1656441Y1021129
X1656441Y1081365
X1656141Y1054593
X1656441Y1067979
X1656441Y1074672
X1656141Y1027822
X1656141Y1034514
X1656141Y1041207
X1656141Y1047900
X1656441Y0937467
X1656441Y0934121
X1656441Y0967585
X1656441Y0944160
X1656441Y0950853
X1656441Y0920735
X1656441Y0927428
X1656441Y0974278
X1656441Y0980971
X1613083Y0893963
X1596941Y0900656
X1613083Y0897310
X1596941Y0897310
X1613083Y0887270
X1596941Y0883924
X1596941Y0890617
X1613083Y0904003
X1613083Y0910696
X1596941Y0907349
X1596941Y0914042
X1656441Y0827034
X1656441Y0863845
X1656441Y0823688
X1656441Y0860499
X1656441Y0870538
X1656441Y0877231
X1656441Y0810302
X1656441Y0816995
X1656441Y0833727
X1656441Y0840420
X1656441Y0847113
X1656441Y0853806
X1613083Y0880577
X1672583Y0820341
X1672583Y0857152
X1672583Y0823688
X1672583Y0860499
X1672583Y0806955
X1672583Y0813648
X1672583Y0830381
X1672583Y0837074
X1672583Y0843766
X1672583Y0850459
X1672583Y0867192
X1672583Y0873885
X1672583Y0970932
X1672583Y0930774
X1672583Y0934121
X1672583Y0964239
X1702283Y0964239
X1686141Y0967585
X1672583Y0940814
X1672583Y0947507
X1672583Y0917389
X1672583Y0924081
X1672583Y0977625
X1672583Y0984318
X1672583Y0991011
X1672583Y1078018
X1672583Y1081365
X1672583Y1051247
X1702283Y1051247
X1686141Y1054593
X1672583Y1064633
X1672583Y1071325
X1672583Y1031168
X1672283Y1037861
X1672283Y1044554
X1672583Y1024475
X1702283Y1024475
X1672583Y1021129
X1702283Y1021129
X1672583Y1151640
X1672583Y1154987
X1672583Y1138255
X1672583Y1144947
X1672583Y1161680
X1672583Y1168373
X1672583Y1088058
X1672583Y1094751
X1672583Y1225262
X1672583Y1228609
X1672583Y1211877
X1672583Y1218569
X1672583Y1235302
X1672583Y1241995
M00
X0061157Y0069340
X0064557Y0069340
X0127157Y0069340
X0141557Y0075340
X0149157Y0069340
X0164761Y0075340
X0075557Y0075340
X0083157Y0069340
X0097557Y0075340
X0105157Y0069340
X0119557Y0075340
X0130557Y0069340
X0138157Y0075340
X0152557Y0069340
X0161361Y0075340
X0072157Y0075340
X0086557Y0069340
X0094157Y0075340
X0108557Y0069340
X0116157Y0075340
X0269957Y1602380
X0257897Y1602380
X0245837Y1602380
X0233777Y1602380
X0221717Y1602380
X0206257Y1602380
X0197597Y1602380
X0266557Y1602380
X0254497Y1602380
X0242437Y1602380
X0230377Y1602380
X0218317Y1602380
X0209657Y1602380
X0194197Y1602380
X0172361Y0069340
X0186761Y0075340
X0194361Y0069340
X0208895Y0075340
X0216495Y0069340
X0230895Y0075340
X0175761Y0069340
X0183361Y0075340
X0197761Y0069340
X0205495Y0075340
X0219895Y0069340
X0227495Y0075340
X0306137Y1602380
X0294077Y1602380
X0282017Y1602380
X0366437Y1602380
X0354377Y1602380
X0342317Y1602380
X0326857Y1602380
X0318197Y1602380
X0302737Y1602380
X0290677Y1602380
X0278617Y1602380
X0363037Y1602380
X0350977Y1602380
X0338917Y1602380
X0330257Y1602380
X0314797Y1602380
X0378497Y1602380
X0375097Y1602380
X0554111Y1602380
X0566171Y1602380
X0481751Y1602380
X0493811Y1602380
X0505871Y1602380
X0517931Y1602380
X0529991Y1602380
X0542051Y1602380
X0550711Y1602380
X0562771Y1602380
X0478351Y1602380
X0490411Y1602380
X0502471Y1602380
X0514531Y1602380
X0526591Y1602380
X0538651Y1602380
X0578231Y1602380
X0590291Y1602380
X0602351Y1602380
X0614411Y1602380
X0626471Y1602380
X0638531Y1602380
X0650591Y1602380
X0659251Y1602380
X0574831Y1602380
X0586891Y1602380
X0598951Y1602380
X0611011Y1602380
X0623071Y1602380
X0635131Y1602380
X0647191Y1602380
X0662651Y1602380
X1032433Y0000189
X1032433Y-0003211
X1153370Y0638192
X1169820Y0636052
X1156770Y0638192
X1165260Y0642112
X1161860Y0642112
X1260472Y1578182
X1248412Y1578182
X1236352Y1578182
X1224292Y1578182
X1208832Y1578182
X1200172Y1578182
X1269132Y1578182
X1257072Y1578182
X1245012Y1578182
X1232952Y1578182
X1220892Y1578182
X1212232Y1578182
X1196772Y1578182
X1173220Y0636052
X1186760Y0642062
X1183360Y0642062
X1341752Y-0003211
X1341752Y0000189
X1290291Y0000189
X1290291Y-0003211
X1308712Y1578182
X1296652Y1578182
X1284592Y1578182
X1272532Y1578182
X1369012Y1578182
X1356952Y1578182
X1344892Y1578182
X1329432Y1578182
X1320772Y1578182
X1305312Y1578182
X1293252Y1578182
X1281192Y1578182
X1365612Y1578182
X1353552Y1578182
X1341492Y1578182
X1332832Y1578182
X1317372Y1578182
X1470995Y1602380
X1467595Y1602380
X1381072Y1578182
X1377672Y1578182
X1400985Y0240929
X1410820Y0220018
X1404385Y0240929
X1407420Y0220018
X1535596Y0069297
X1549996Y0075297
X1557596Y0069297
X1538996Y0069297
X1546596Y0075297
X1560996Y0069297
X1568596Y0075297
X1482650Y-0003211
X1482650Y0000189
X1543355Y1602380
X1555415Y1602380
X1567475Y1602380
X1483055Y1602380
X1495115Y1602380
X1507175Y1602380
X1519235Y1602380
X1531295Y1602380
X1539955Y1602380
X1552015Y1602380
X1564075Y1602380
X1479655Y1602380
X1491715Y1602380
X1503775Y1602380
X1515835Y1602380
X1527895Y1602380
X1579535Y1602380
X1591595Y1602380
X1603655Y1602380
X1615715Y1602380
X1627775Y1602380
X1639835Y1602380
X1648495Y1602380
X1576135Y1602380
X1588195Y1602380
X1600255Y1602380
X1612315Y1602380
X1624375Y1602380
X1636435Y1602380
X1651895Y1602380
X1601596Y0069297
X1615996Y0075297
X1623596Y0069297
X1639200Y0075297
X1646800Y0069297
X1661200Y0075297
X1668800Y0069297
X1571996Y0075297
X1579596Y0069297
X1593996Y0075297
X1604996Y0069297
X1612596Y0075297
X1626996Y0069297
X1635800Y0075297
X1650200Y0069297
X1657800Y0075297
X1582996Y0069297
X1590596Y0075297
X1683334Y0075297
X1690934Y0069297
X1701934Y0075297
X1672200Y0069297
X1679934Y0075297
X1694334Y0069297
X1705334Y0075297
M30
